# T6G (Grand Teton) — schematic netlist excerpt (pin names and nets, part order shuffled) for the footprints in the layout excerpt that follows; sources: Cadence DE-HDL packaged netlist, KiCad conversion of 04192023_DAF0TMB3IC0_F0TG_MB_C_brd_V02_OCP.brd

PC2231  Q_CAP  1UF 25V 10% X6S  pkg C0402  page 152 : A = P12V_AUX ; B = GND
R1368  Q_RES  4.7K 5% CHIP  pkg 0201LF  page 276 : A = CLKREQ_RT_CPU0_P0_N ; B = GND
R8010  Q_RES  0 5% EMPTY  pkg 0402LF  page 224 : A = PVDD11_S3_P1_OCP_N ; B = PVDD11_S3_P1_OCP_N_R

(kicad_pcb
	(version 20260206)
	(generator "pcbnew")
	(generator_version "10.0")
	(general
		(thickness 1.6)
		(legacy_teardrops no)
	)
	(paper "A4")
	(title_block
		(title "04192023_DAF0TMB3IC0_F0TG_MB_C_brd_V02_OCP.brd")
		(comment 1 "Grand Teton / footprints 1336-1338 of 8354")
	)
	(layers
		(0 "F.Cu" signal "TOP")
		(4 "In1.Cu" signal "GND")
		(6 "In2.Cu" signal "IN1")
		(8 "In3.Cu" signal "GND1")
		(10 "In4.Cu" signal "IN2")
		(12 "In5.Cu" signal "GND2")
		(14 "In6.Cu" signal "IN3")
		(16 "In7.Cu" signal "GND3")
		(18 "In8.Cu" signal "VCC")
		(20 "In9.Cu" signal "VCC1")
		(22 "In10.Cu" signal "GND4")
		(24 "In11.Cu" signal "IN4")
		(26 "In12.Cu" signal "GND5")
		(28 "In13.Cu" signal "IN5")
		(30 "In14.Cu" signal "GND6")
		(32 "In15.Cu" signal "IN6")
		(34 "In16.Cu" signal "GND7")
		(2 "B.Cu" signal "BOTTOM")
		(9 "F.Adhes" user "F.Adhesive")
		(11 "B.Adhes" user "B.Adhesive")
		(13 "F.Paste" user "Package Geometry/Pastemask Top")
		(15 "B.Paste" user "Package Geometry/Pastemask Bottom")
		(5 "F.SilkS" user "Ref Des/Silkscreen Top")
		(7 "B.SilkS" user "Ref Des/Silkscreen Bottom")
		(1 "F.Mask" user "Board Geometry/Soldermask Top")
		(3 "B.Mask" user "Board Geometry/Soldermask Bottom")
		(17 "Dwgs.User" user "User.Drawings")
		(19 "Cmts.User" user "User.Comments")
		(21 "Eco1.User" user "User.Eco1")
		(23 "Eco2.User" user "User.Eco2")
		(25 "Edge.Cuts" user "Board Geometry/Outline")
		(27 "Margin" user)
		(31 "F.CrtYd" user "Package Geometry/Place Bound Top")
		(29 "B.CrtYd" user "Package Geometry/Place Bound Bottom")
		(35 "F.Fab" user "Ref Des/Assembly Top")
		(33 "B.Fab" user "Ref Des/Assembly Bottom")
	)
	(footprint ""
		(layer "F.Cu")
		(at 183.878982 -34.794952 90)
		(property "Reference" "PC2231"
			(at 0 0 90)
			(layer "F.SilkS")
			(hide yes)
			(effects
				(font
					(size 1.27 1.27)
				)
			)
		)
		(property "Value" ""
			(at 0 0 90)
			(layer "F.Fab")
			(effects
				(font
					(size 1.27 1.27)
				)
			)
		)
		(duplicate_pad_numbers_are_jumpers no)
		(fp_line
			(start 0.7874 -0.4064)
			(end 0.7874 0.4064)
			(stroke
				(width 0.1524)
				(type default)
			)
			(layer "F.SilkS")
		)
		(fp_line
			(start -0.7874 -0.4064)
			(end 0.7874 -0.4064)
			(stroke
				(width 0.1524)
				(type default)
			)
			(layer "F.SilkS")
		)
		(fp_line
			(start 0.7874 0.4064)
			(end -0.7874 0.4064)
			(stroke
				(width 0.1524)
				(type default)
			)
			(layer "F.SilkS")
		)
		(fp_line
			(start -0.7874 0.4064)
			(end -0.7874 -0.4064)
			(stroke
				(width 0.1524)
				(type default)
			)
			(layer "F.SilkS")
		)
		(fp_line
			(start -0.12065 -0.305054)
			(end -0.12065 -0.2794)
			(stroke
				(width 0.1)
				(type default)
			)
			(layer "F.Fab")
		)
		(fp_line
			(start -0.67945 -0.305054)
			(end -0.12065 -0.305054)
			(stroke
				(width 0.1)
				(type default)
			)
			(layer "F.Fab")
		)
		(fp_line
			(start 0.67945 -0.3048)
			(end 0.67945 0.3048)
			(stroke
				(width 0.1)
				(type default)
			)
			(layer "F.Fab")
		)
		(fp_line
			(start 0.12065 -0.3048)
			(end 0.67945 -0.3048)
			(stroke
				(width 0.1)
				(type default)
			)
			(layer "F.Fab")
		)
		(fp_line
			(start 0.12065 -0.2794)
			(end 0.12065 -0.3048)
			(stroke
				(width 0.1)
				(type default)
			)
			(layer "F.Fab")
		)
		(fp_line
			(start -0.12065 -0.2794)
			(end 0.12065 -0.2794)
			(stroke
				(width 0.1)
				(type default)
			)
			(layer "F.Fab")
		)
		(fp_line
			(start 0.120396 0.2794)
			(end -0.12065 0.2794)
			(stroke
				(width 0.1)
				(type default)
			)
			(layer "F.Fab")
		)
		(fp_line
			(start -0.12065 0.2794)
			(end -0.12065 0.3048)
			(stroke
				(width 0.1)
				(type default)
			)
			(layer "F.Fab")
		)
		(fp_line
			(start 0.67945 0.3048)
			(end 0.120396 0.3048)
			(stroke
				(width 0.1)
				(type default)
			)
			(layer "F.Fab")
		)
		(fp_line
			(start 0.120396 0.3048)
			(end 0.120396 0.2794)
			(stroke
				(width 0.1)
				(type default)
			)
			(layer "F.Fab")
		)
		(fp_line
			(start -0.12065 0.3048)
			(end -0.67945 0.3048)
			(stroke
				(width 0.1)
				(type default)
			)
			(layer "F.Fab")
		)
		(fp_line
			(start -0.67945 0.3048)
			(end -0.67945 -0.305054)
			(stroke
				(width 0.1)
				(type default)
			)
			(layer "F.Fab")
		)
		(pad "1" smd circle
			(at -0.40005 0 90)
			(size 0 0)
			(layers "F.Cu" "F.Mask" "F.Paste")
			(net "P12V_AUX")
		)
		(pad "2" smd circle
			(at 0.40005 0 90)
			(size 0 0)
			(layers "F.Cu" "F.Mask" "F.Paste")
			(net "GND")
		)
	)
	(footprint ""
		(layer "F.Cu")
		(at 166.934388 -346.302076 180)
		(property "Reference" "R8010"
			(at 0 0 180)
			(layer "F.SilkS")
			(hide yes)
			(effects
				(font
					(size 1.27 1.27)
				)
			)
		)
		(property "Value" ""
			(at 0 0 180)
			(layer "F.Fab")
			(effects
				(font
					(size 1.27 1.27)
				)
			)
		)
		(duplicate_pad_numbers_are_jumpers no)
		(fp_line
			(start 0.7874 0.4064)
			(end -0.7874 0.4064)
			(stroke
				(width 0.1524)
				(type default)
			)
			(layer "F.SilkS")
		)
		(fp_line
			(start 0.7874 -0.4064)
			(end 0.7874 0.4064)
			(stroke
				(width 0.1524)
				(type default)
			)
			(layer "F.SilkS")
		)
		(fp_line
			(start -0.7874 0.4064)
			(end -0.7874 -0.4064)
			(stroke
				(width 0.1524)
				(type default)
			)
			(layer "F.SilkS")
		)
		(fp_line
			(start -0.7874 -0.4064)
			(end 0.7874 -0.4064)
			(stroke
				(width 0.1524)
				(type default)
			)
			(layer "F.SilkS")
		)
		(fp_line
			(start 0.67945 0.3048)
			(end 0.120396 0.3048)
			(stroke
				(width 0.1)
				(type default)
			)
			(layer "F.Fab")
		)
		(fp_line
			(start 0.67945 -0.3048)
			(end 0.67945 0.3048)
			(stroke
				(width 0.1)
				(type default)
			)
			(layer "F.Fab")
		)
		(fp_line
			(start 0.12065 -0.2794)
			(end 0.12065 -0.3048)
			(stroke
				(width 0.1)
				(type default)
			)
			(layer "F.Fab")
		)
		(fp_line
			(start 0.12065 -0.3048)
			(end 0.67945 -0.3048)
			(stroke
				(width 0.1)
				(type default)
			)
			(layer "F.Fab")
		)
		(fp_line
			(start 0.120396 0.3048)
			(end 0.120396 0.2794)
			(stroke
				(width 0.1)
				(type default)
			)
			(layer "F.Fab")
		)
		(fp_line
			(start 0.120396 0.2794)
			(end -0.12065 0.2794)
			(stroke
				(width 0.1)
				(type default)
			)
			(layer "F.Fab")
		)
		(fp_line
			(start -0.12065 0.3048)
			(end -0.67945 0.3048)
			(stroke
				(width 0.1)
				(type default)
			)
			(layer "F.Fab")
		)
		(fp_line
			(start -0.12065 0.2794)
			(end -0.12065 0.3048)
			(stroke
				(width 0.1)
				(type default)
			)
			(layer "F.Fab")
		)
		(fp_line
			(start -0.12065 -0.2794)
			(end 0.12065 -0.2794)
			(stroke
				(width 0.1)
				(type default)
			)
			(layer "F.Fab")
		)
		(fp_line
			(start -0.12065 -0.305054)
			(end -0.12065 -0.2794)
			(stroke
				(width 0.1)
				(type default)
			)
			(layer "F.Fab")
		)
		(fp_line
			(start -0.67945 0.3048)
			(end -0.67945 -0.305054)
			(stroke
				(width 0.1)
				(type default)
			)
			(layer "F.Fab")
		)
		(fp_line
			(start -0.67945 -0.305054)
			(end -0.12065 -0.305054)
			(stroke
				(width 0.1)
				(type default)
			)
			(layer "F.Fab")
		)
		(pad "1" smd circle
			(at -0.40005 0 180)
			(size 0 0)
			(layers "F.Cu" "F.Mask" "F.Paste")
			(net "PVDD11_S3_P1_OCP_N")
		)
		(pad "2" smd circle
			(at 0.40005 0 180)
			(size 0 0)
			(layers "F.Cu" "F.Mask" "F.Paste")
			(net "PVDD11_S3_P1_OCP_N_R")
		)
	)
	(footprint ""
		(layer "F.Cu")
		(at 326.967342 -390.1694)
		(property "Reference" "R1368"
			(at 0 0 0)
			(layer "F.SilkS")
			(hide yes)
			(effects
				(font
					(size 1.27 1.27)
				)
			)
		)
		(property "Value" ""
			(at 0 0 0)
			(layer "F.Fab")
			(effects
				(font
					(size 1.27 1.27)
				)
			)
		)
		(duplicate_pad_numbers_are_jumpers no)
		(fp_line
			(start -0.32512 -0.175006)
			(end 0.32512 -0.175006)
			(stroke
				(width 0.1)
				(type default)
			)
			(layer "F.Fab")
		)
		(fp_line
			(start -0.32512 0.175006)
			(end -0.32512 -0.175006)
			(stroke
				(width 0.1)
				(type default)
			)
			(layer "F.Fab")
		)
		(fp_line
			(start 0.32512 -0.175006)
			(end 0.32512 0.175006)
			(stroke
				(width 0.1)
				(type default)
			)
			(layer "F.Fab")
		)
		(fp_line
			(start 0.32512 0.175006)
			(end -0.32512 0.175006)
			(stroke
				(width 0.1)
				(type default)
			)
			(layer "F.Fab")
		)
		(pad "1" smd rect
			(at -0.2667 0)
			(size 0.3048 0.381)
			(layers "F.Cu" "F.Mask" "F.Paste")
			(net "CLKREQ_RT_CPU0_P0_N")
		)
		(pad "2" smd rect
			(at 0.2667 0 180)
			(size 0.3048 0.381)
			(layers "F.Cu" "F.Mask" "F.Paste")
			(net "GND")
		)
	)
)
